(kicad_pcb
	(version 20260206)
	(generator "pcbnew")
	(generator_version "10.0")
	(general
		(thickness 1.6)
		(legacy_teardrops no)
	)
	(paper "A4")
	(title_block
		(title "03242023_DA0F0TMBIJ0_F0T_Motherboard_J_brd_V01_OCP.brd")
		(comment 1 "Grand Teton / footprints 3406-3411 of 6105")
	)
	(layers
		(0 "F.Cu" signal "TOP")
		(4 "In1.Cu" signal "GND")
		(6 "In2.Cu" signal "IN1")
		(8 "In3.Cu" signal "GND1")
		(10 "In4.Cu" signal "IN2")
		(12 "In5.Cu" signal "GND2")
		(14 "In6.Cu" signal "IN3")
		(16 "In7.Cu" signal "GND3")
		(18 "In8.Cu" signal "VCC")
		(20 "In9.Cu" signal "VCC1")
		(22 "In10.Cu" signal "GND4")
		(24 "In11.Cu" signal "IN4")
		(26 "In12.Cu" signal "GND5")
		(28 "In13.Cu" signal "IN5")
		(30 "In14.Cu" signal "GND6")
		(32 "In15.Cu" signal "IN6")
		(34 "In16.Cu" signal "GND7")
		(2 "B.Cu" signal "BOTTOM")
		(9 "F.Adhes" user "F.Adhesive")
		(11 "B.Adhes" user "B.Adhesive")
		(13 "F.Paste" user "Package Geometry/Pastemask Top")
		(15 "B.Paste" user "Package Geometry/Pastemask Bottom")
		(5 "F.SilkS" user "Ref Des/Silkscreen Top")
		(7 "B.SilkS" user "Ref Des/Silkscreen Bottom")
		(1 "F.Mask" user "Board Geometry/Soldermask Top")
		(3 "B.Mask" user "Board Geometry/Soldermask Bottom")
		(17 "Dwgs.User" user "User.Drawings")
		(19 "Cmts.User" user "User.Comments")
		(21 "Eco1.User" user "User.Eco1")
		(23 "Eco2.User" user "User.Eco2")
		(25 "Edge.Cuts" user "Board Geometry/Outline")
		(27 "Margin" user)
		(31 "F.CrtYd" user "Package Geometry/Place Bound Top")
		(29 "B.CrtYd" user "Package Geometry/Place Bound Bottom")
		(35 "F.Fab" user "Ref Des/Assembly Top")
		(33 "B.Fab" user "Ref Des/Assembly Bottom")
	)
	(footprint ""
		(layer "F.Cu")
		(at 7.42188 -56.987948)
		(property "Reference" "R2995"
			(at 0 0 0)
			(layer "F.SilkS")
			(hide yes)
			(effects
				(font
					(size 1.27 1.27)
				)
			)
		)
		(property "Value" ""
			(at 0 0 0)
			(layer "F.Fab")
			(effects
				(font
					(size 1.27 1.27)
				)
			)
		)
		(duplicate_pad_numbers_are_jumpers no)
		(fp_line
			(start -0.7874 -0.4064)
			(end 0.7874 -0.4064)
			(stroke
				(width 0.1524)
				(type default)
			)
			(layer "F.SilkS")
		)
		(fp_line
			(start -0.7874 0.4064)
			(end -0.7874 -0.4064)
			(stroke
				(width 0.1524)
				(type default)
			)
			(layer "F.SilkS")
		)
		(fp_line
			(start 0.7874 -0.4064)
			(end 0.7874 0.4064)
			(stroke
				(width 0.1524)
				(type default)
			)
			(layer "F.SilkS")
		)
		(fp_line
			(start 0.7874 0.4064)
			(end -0.7874 0.4064)
			(stroke
				(width 0.1524)
				(type default)
			)
			(layer "F.SilkS")
		)
		(fp_line
			(start -0.67945 -0.305054)
			(end -0.12065 -0.305054)
			(stroke
				(width 0.1)
				(type default)
			)
			(layer "F.Fab")
		)
		(fp_line
			(start -0.67945 0.3048)
			(end -0.67945 -0.305054)
			(stroke
				(width 0.1)
				(type default)
			)
			(layer "F.Fab")
		)
		(fp_line
			(start -0.12065 -0.305054)
			(end -0.12065 -0.2794)
			(stroke
				(width 0.1)
				(type default)
			)
			(layer "F.Fab")
		)
		(fp_line
			(start -0.12065 -0.2794)
			(end 0.12065 -0.2794)
			(stroke
				(width 0.1)
				(type default)
			)
			(layer "F.Fab")
		)
		(fp_line
			(start -0.12065 0.2794)
			(end -0.12065 0.3048)
			(stroke
				(width 0.1)
				(type default)
			)
			(layer "F.Fab")
		)
		(fp_line
			(start -0.12065 0.3048)
			(end -0.67945 0.3048)
			(stroke
				(width 0.1)
				(type default)
			)
			(layer "F.Fab")
		)
		(fp_line
			(start 0.120396 0.2794)
			(end -0.12065 0.2794)
			(stroke
				(width 0.1)
				(type default)
			)
			(layer "F.Fab")
		)
		(fp_line
			(start 0.120396 0.3048)
			(end 0.120396 0.2794)
			(stroke
				(width 0.1)
				(type default)
			)
			(layer "F.Fab")
		)
		(fp_line
			(start 0.12065 -0.3048)
			(end 0.67945 -0.3048)
			(stroke
				(width 0.1)
				(type default)
			)
			(layer "F.Fab")
		)
		(fp_line
			(start 0.12065 -0.2794)
			(end 0.12065 -0.3048)
			(stroke
				(width 0.1)
				(type default)
			)
			(layer "F.Fab")
		)
		(fp_line
			(start 0.67945 -0.3048)
			(end 0.67945 0.3048)
			(stroke
				(width 0.1)
				(type default)
			)
			(layer "F.Fab")
		)
		(fp_line
			(start 0.67945 0.3048)
			(end 0.120396 0.3048)
			(stroke
				(width 0.1)
				(type default)
			)
			(layer "F.Fab")
		)
		(pad "1" smd circle
			(at -0.40005 0)
			(size 0 0)
			(layers "F.Cu" "F.Mask" "F.Paste")
			(net "SMB_SML1_PMBUS_3V3AUX_PCH_SCL")
		)
		(pad "2" smd circle
			(at 0.40005 0)
			(size 0 0)
			(layers "F.Cu" "F.Mask" "F.Paste")
			(net "SMB_SML1_PMBUS_HSC_SCL_R3")
		)
	)
	(footprint ""
		(layer "F.Cu")
		(at 397.403066 -166.475664)
		(property "Reference" "PR592"
			(at 0 0 0)
			(layer "F.SilkS")
			(hide yes)
			(effects
				(font
					(size 1.27 1.27)
				)
			)
		)
		(property "Value" ""
			(at 0 0 0)
			(layer "F.Fab")
			(effects
				(font
					(size 1.27 1.27)
				)
			)
		)
		(duplicate_pad_numbers_are_jumpers no)
		(fp_line
			(start -0.7874 -0.4064)
			(end 0.7874 -0.4064)
			(stroke
				(width 0.1524)
				(type default)
			)
			(layer "F.SilkS")
		)
		(fp_line
			(start -0.7874 0.4064)
			(end -0.7874 -0.4064)
			(stroke
				(width 0.1524)
				(type default)
			)
			(layer "F.SilkS")
		)
		(fp_line
			(start 0.7874 -0.4064)
			(end 0.7874 0.4064)
			(stroke
				(width 0.1524)
				(type default)
			)
			(layer "F.SilkS")
		)
		(fp_line
			(start 0.7874 0.4064)
			(end -0.7874 0.4064)
			(stroke
				(width 0.1524)
				(type default)
			)
			(layer "F.SilkS")
		)
		(fp_line
			(start -0.67945 -0.305054)
			(end -0.12065 -0.305054)
			(stroke
				(width 0.1)
				(type default)
			)
			(layer "F.Fab")
		)
		(fp_line
			(start -0.67945 0.3048)
			(end -0.67945 -0.305054)
			(stroke
				(width 0.1)
				(type default)
			)
			(layer "F.Fab")
		)
		(fp_line
			(start -0.12065 -0.305054)
			(end -0.12065 -0.2794)
			(stroke
				(width 0.1)
				(type default)
			)
			(layer "F.Fab")
		)
		(fp_line
			(start -0.12065 -0.2794)
			(end 0.12065 -0.2794)
			(stroke
				(width 0.1)
				(type default)
			)
			(layer "F.Fab")
		)
		(fp_line
			(start -0.12065 0.2794)
			(end -0.12065 0.3048)
			(stroke
				(width 0.1)
				(type default)
			)
			(layer "F.Fab")
		)
		(fp_line
			(start -0.12065 0.3048)
			(end -0.67945 0.3048)
			(stroke
				(width 0.1)
				(type default)
			)
			(layer "F.Fab")
		)
		(fp_line
			(start 0.120396 0.2794)
			(end -0.12065 0.2794)
			(stroke
				(width 0.1)
				(type default)
			)
			(layer "F.Fab")
		)
		(fp_line
			(start 0.120396 0.3048)
			(end 0.120396 0.2794)
			(stroke
				(width 0.1)
				(type default)
			)
			(layer "F.Fab")
		)
		(fp_line
			(start 0.12065 -0.3048)
			(end 0.67945 -0.3048)
			(stroke
				(width 0.1)
				(type default)
			)
			(layer "F.Fab")
		)
		(fp_line
			(start 0.12065 -0.2794)
			(end 0.12065 -0.3048)
			(stroke
				(width 0.1)
				(type default)
			)
			(layer "F.Fab")
		)
		(fp_line
			(start 0.67945 -0.3048)
			(end 0.67945 0.3048)
			(stroke
				(width 0.1)
				(type default)
			)
			(layer "F.Fab")
		)
		(fp_line
			(start 0.67945 0.3048)
			(end 0.120396 0.3048)
			(stroke
				(width 0.1)
				(type default)
			)
			(layer "F.Fab")
		)
		(pad "1" smd circle
			(at -0.40005 0)
			(size 0 0)
			(layers "F.Cu" "F.Mask" "F.Paste")
			(net "VSENSE_PVCCD_HV_CPU0_DP")
		)
		(pad "2" smd circle
			(at 0.40005 0)
			(size 0 0)
			(layers "F.Cu" "F.Mask" "F.Paste")
			(net "PVCCD_HV_CPU0")
		)
	)
	(footprint ""
		(layer "F.Cu")
		(at 180.776626 -416.903154 -90)
		(property "Reference" "C1751"
			(at 0 0 270)
			(layer "F.SilkS")
			(hide yes)
			(effects
				(font
					(size 1.27 1.27)
				)
			)
		)
		(property "Value" ""
			(at 0 0 270)
			(layer "F.Fab")
			(effects
				(font
					(size 1.27 1.27)
				)
			)
		)
		(duplicate_pad_numbers_are_jumpers no)
		(fp_line
			(start -0.7874 0.4064)
			(end -0.7874 -0.4064)
			(stroke
				(width 0.1524)
				(type default)
			)
			(layer "F.SilkS")
		)
		(fp_line
			(start 0.7874 0.4064)
			(end -0.7874 0.4064)
			(stroke
				(width 0.1524)
				(type default)
			)
			(layer "F.SilkS")
		)
		(fp_line
			(start -0.7874 -0.4064)
			(end 0.7874 -0.4064)
			(stroke
				(width 0.1524)
				(type default)
			)
			(layer "F.SilkS")
		)
		(fp_line
			(start 0.7874 -0.4064)
			(end 0.7874 0.4064)
			(stroke
				(width 0.1524)
				(type default)
			)
			(layer "F.SilkS")
		)
		(fp_line
			(start -0.67945 0.3048)
			(end -0.67945 -0.305054)
			(stroke
				(width 0.1)
				(type default)
			)
			(layer "F.Fab")
		)
		(fp_line
			(start -0.12065 0.3048)
			(end -0.67945 0.3048)
			(stroke
				(width 0.1)
				(type default)
			)
			(layer "F.Fab")
		)
		(fp_line
			(start 0.120396 0.3048)
			(end 0.120396 0.2794)
			(stroke
				(width 0.1)
				(type default)
			)
			(layer "F.Fab")
		)
		(fp_line
			(start 0.67945 0.3048)
			(end 0.120396 0.3048)
			(stroke
				(width 0.1)
				(type default)
			)
			(layer "F.Fab")
		)
		(fp_line
			(start -0.12065 0.2794)
			(end -0.12065 0.3048)
			(stroke
				(width 0.1)
				(type default)
			)
			(layer "F.Fab")
		)
		(fp_line
			(start 0.120396 0.2794)
			(end -0.12065 0.2794)
			(stroke
				(width 0.1)
				(type default)
			)
			(layer "F.Fab")
		)
		(fp_line
			(start -0.12065 -0.2794)
			(end 0.12065 -0.2794)
			(stroke
				(width 0.1)
				(type default)
			)
			(layer "F.Fab")
		)
		(fp_line
			(start 0.12065 -0.2794)
			(end 0.12065 -0.3048)
			(stroke
				(width 0.1)
				(type default)
			)
			(layer "F.Fab")
		)
		(fp_line
			(start 0.12065 -0.3048)
			(end 0.67945 -0.3048)
			(stroke
				(width 0.1)
				(type default)
			)
			(layer "F.Fab")
		)
		(fp_line
			(start 0.67945 -0.3048)
			(end 0.67945 0.3048)
			(stroke
				(width 0.1)
				(type default)
			)
			(layer "F.Fab")
		)
		(fp_line
			(start -0.67945 -0.305054)
			(end -0.12065 -0.305054)
			(stroke
				(width 0.1)
				(type default)
			)
			(layer "F.Fab")
		)
		(fp_line
			(start -0.12065 -0.305054)
			(end -0.12065 -0.2794)
			(stroke
				(width 0.1)
				(type default)
			)
			(layer "F.Fab")
		)
		(pad "1" smd circle
			(at -0.40005 0 270)
			(size 0 0)
			(layers "F.Cu" "F.Mask" "F.Paste")
			(net "P3V3_AUX")
		)
		(pad "2" smd circle
			(at 0.40005 0 270)
			(size 0 0)
			(layers "F.Cu" "F.Mask" "F.Paste")
			(net "GND")
		)
	)
	(footprint ""
		(layer "F.Cu")
		(at 169.44848 -424.906948)
		(property "Reference" "R2815"
			(at 0 0 0)
			(layer "F.SilkS")
			(hide yes)
			(effects
				(font
					(size 1.27 1.27)
				)
			)
		)
		(property "Value" ""
			(at 0 0 0)
			(layer "F.Fab")
			(effects
				(font
					(size 1.27 1.27)
				)
			)
		)
		(duplicate_pad_numbers_are_jumpers no)
		(fp_line
			(start -0.7874 -0.4064)
			(end 0.7874 -0.4064)
			(stroke
				(width 0.1524)
				(type default)
			)
			(layer "F.SilkS")
		)
		(fp_line
			(start -0.7874 0.4064)
			(end -0.7874 -0.4064)
			(stroke
				(width 0.1524)
				(type default)
			)
			(layer "F.SilkS")
		)
		(fp_line
			(start 0.7874 -0.4064)
			(end 0.7874 0.4064)
			(stroke
				(width 0.1524)
				(type default)
			)
			(layer "F.SilkS")
		)
		(fp_line
			(start 0.7874 0.4064)
			(end -0.7874 0.4064)
			(stroke
				(width 0.1524)
				(type default)
			)
			(layer "F.SilkS")
		)
		(fp_line
			(start -0.67945 -0.305054)
			(end -0.12065 -0.305054)
			(stroke
				(width 0.1)
				(type default)
			)
			(layer "F.Fab")
		)
		(fp_line
			(start -0.67945 0.3048)
			(end -0.67945 -0.305054)
			(stroke
				(width 0.1)
				(type default)
			)
			(layer "F.Fab")
		)
		(fp_line
			(start -0.12065 -0.305054)
			(end -0.12065 -0.2794)
			(stroke
				(width 0.1)
				(type default)
			)
			(layer "F.Fab")
		)
		(fp_line
			(start -0.12065 -0.2794)
			(end 0.12065 -0.2794)
			(stroke
				(width 0.1)
				(type default)
			)
			(layer "F.Fab")
		)
		(fp_line
			(start -0.12065 0.2794)
			(end -0.12065 0.3048)
			(stroke
				(width 0.1)
				(type default)
			)
			(layer "F.Fab")
		)
		(fp_line
			(start -0.12065 0.3048)
			(end -0.67945 0.3048)
			(stroke
				(width 0.1)
				(type default)
			)
			(layer "F.Fab")
		)
		(fp_line
			(start 0.120396 0.2794)
			(end -0.12065 0.2794)
			(stroke
				(width 0.1)
				(type default)
			)
			(layer "F.Fab")
		)
		(fp_line
			(start 0.120396 0.3048)
			(end 0.120396 0.2794)
			(stroke
				(width 0.1)
				(type default)
			)
			(layer "F.Fab")
		)
		(fp_line
			(start 0.12065 -0.3048)
			(end 0.67945 -0.3048)
			(stroke
				(width 0.1)
				(type default)
			)
			(layer "F.Fab")
		)
		(fp_line
			(start 0.12065 -0.2794)
			(end 0.12065 -0.3048)
			(stroke
				(width 0.1)
				(type default)
			)
			(layer "F.Fab")
		)
		(fp_line
			(start 0.67945 -0.3048)
			(end 0.67945 0.3048)
			(stroke
				(width 0.1)
				(type default)
			)
			(layer "F.Fab")
		)
		(fp_line
			(start 0.67945 0.3048)
			(end 0.120396 0.3048)
			(stroke
				(width 0.1)
				(type default)
			)
			(layer "F.Fab")
		)
		(pad "1" smd circle
			(at -0.40005 0)
			(size 0 0)
			(layers "F.Cu" "F.Mask" "F.Paste")
			(net "P3V3_AUX")
		)
		(pad "2" smd circle
			(at 0.40005 0)
			(size 0 0)
			(layers "F.Cu" "F.Mask" "F.Paste")
			(net "BMC_MONITER_R")
		)
	)
	(footprint ""
		(layer "F.Cu")
		(at 49.161954 -173.047914)
		(property "Reference" "PC1366"
			(at 0 0 0)
			(layer "F.SilkS")
			(hide yes)
			(effects
				(font
					(size 1.27 1.27)
				)
			)
		)
		(property "Value" ""
			(at 0 0 0)
			(layer "F.Fab")
			(effects
				(font
					(size 1.27 1.27)
				)
			)
		)
		(duplicate_pad_numbers_are_jumpers no)
		(fp_line
			(start -0.7874 -0.4064)
			(end 0.7874 -0.4064)
			(stroke
				(width 0.1524)
				(type default)
			)
			(layer "F.SilkS")
		)
		(fp_line
			(start -0.7874 0.4064)
			(end -0.7874 -0.4064)
			(stroke
				(width 0.1524)
				(type default)
			)
			(layer "F.SilkS")
		)
		(fp_line
			(start 0.7874 -0.4064)
			(end 0.7874 0.4064)
			(stroke
				(width 0.1524)
				(type default)
			)
			(layer "F.SilkS")
		)
		(fp_line
			(start 0.7874 0.4064)
			(end -0.7874 0.4064)
			(stroke
				(width 0.1524)
				(type default)
			)
			(layer "F.SilkS")
		)
		(fp_line
			(start -0.67945 -0.305054)
			(end -0.12065 -0.305054)
			(stroke
				(width 0.1)
				(type default)
			)
			(layer "F.Fab")
		)
		(fp_line
			(start -0.67945 0.3048)
			(end -0.67945 -0.305054)
			(stroke
				(width 0.1)
				(type default)
			)
			(layer "F.Fab")
		)
		(fp_line
			(start -0.12065 -0.305054)
			(end -0.12065 -0.2794)
			(stroke
				(width 0.1)
				(type default)
			)
			(layer "F.Fab")
		)
		(fp_line
			(start -0.12065 -0.2794)
			(end 0.12065 -0.2794)
			(stroke
				(width 0.1)
				(type default)
			)
			(layer "F.Fab")
		)
		(fp_line
			(start -0.12065 0.2794)
			(end -0.12065 0.3048)
			(stroke
				(width 0.1)
				(type default)
			)
			(layer "F.Fab")
		)
		(fp_line
			(start -0.12065 0.3048)
			(end -0.67945 0.3048)
			(stroke
				(width 0.1)
				(type default)
			)
			(layer "F.Fab")
		)
		(fp_line
			(start 0.120396 0.2794)
			(end -0.12065 0.2794)
			(stroke
				(width 0.1)
				(type default)
			)
			(layer "F.Fab")
		)
		(fp_line
			(start 0.120396 0.3048)
			(end 0.120396 0.2794)
			(stroke
				(width 0.1)
				(type default)
			)
			(layer "F.Fab")
		)
		(fp_line
			(start 0.12065 -0.3048)
			(end 0.67945 -0.3048)
			(stroke
				(width 0.1)
				(type default)
			)
			(layer "F.Fab")
		)
		(fp_line
			(start 0.12065 -0.2794)
			(end 0.12065 -0.3048)
			(stroke
				(width 0.1)
				(type default)
			)
			(layer "F.Fab")
		)
		(fp_line
			(start 0.67945 -0.3048)
			(end 0.67945 0.3048)
			(stroke
				(width 0.1)
				(type default)
			)
			(layer "F.Fab")
		)
		(fp_line
			(start 0.67945 0.3048)
			(end 0.120396 0.3048)
			(stroke
				(width 0.1)
				(type default)
			)
			(layer "F.Fab")
		)
		(pad "1" smd circle
			(at -0.40005 0)
			(size 0 0)
			(layers "F.Cu" "F.Mask" "F.Paste")
			(net "GND")
		)
		(pad "2" smd circle
			(at 0.40005 0)
			(size 0 0)
			(layers "F.Cu" "F.Mask" "F.Paste")
			(net "PVCCINFAON_CPU1_VREF")
		)
	)
	(footprint ""
		(layer "F.Cu")
		(at 184.658 -93.91015 90)
		(property "Reference" "R4760"
			(at 0 0 90)
			(layer "F.SilkS")
			(hide yes)
			(effects
				(font
					(size 1.27 1.27)
				)
			)
		)
		(property "Value" ""
			(at 0 0 90)
			(layer "F.Fab")
			(effects
				(font
					(size 1.27 1.27)
				)
			)
		)
		(duplicate_pad_numbers_are_jumpers no)
		(fp_line
			(start 0.7874 -0.4064)
			(end 0.7874 0.4064)
			(stroke
				(width 0.1524)
				(type default)
			)
			(layer "F.SilkS")
		)
		(fp_line
			(start -0.7874 -0.4064)
			(end 0.7874 -0.4064)
			(stroke
				(width 0.1524)
				(type default)
			)
			(layer "F.SilkS")
		)
		(fp_line
			(start 0.7874 0.4064)
			(end -0.7874 0.4064)
			(stroke
				(width 0.1524)
				(type default)
			)
			(layer "F.SilkS")
		)
		(fp_line
			(start -0.7874 0.4064)
			(end -0.7874 -0.4064)
			(stroke
				(width 0.1524)
				(type default)
			)
			(layer "F.SilkS")
		)
		(fp_line
			(start -0.12065 -0.305054)
			(end -0.12065 -0.2794)
			(stroke
				(width 0.1)
				(type default)
			)
			(layer "F.Fab")
		)
		(fp_line
			(start -0.67945 -0.305054)
			(end -0.12065 -0.305054)
			(stroke
				(width 0.1)
				(type default)
			)
			(layer "F.Fab")
		)
		(fp_line
			(start 0.67945 -0.3048)
			(end 0.67945 0.3048)
			(stroke
				(width 0.1)
				(type default)
			)
			(layer "F.Fab")
		)
		(fp_line
			(start 0.12065 -0.3048)
			(end 0.67945 -0.3048)
			(stroke
				(width 0.1)
				(type default)
			)
			(layer "F.Fab")
		)
		(fp_line
			(start 0.12065 -0.2794)
			(end 0.12065 -0.3048)
			(stroke
				(width 0.1)
				(type default)
			)
			(layer "F.Fab")
		)
		(fp_line
			(start -0.12065 -0.2794)
			(end 0.12065 -0.2794)
			(stroke
				(width 0.1)
				(type default)
			)
			(layer "F.Fab")
		)
		(fp_line
			(start 0.120396 0.2794)
			(end -0.12065 0.2794)
			(stroke
				(width 0.1)
				(type default)
			)
			(layer "F.Fab")
		)
		(fp_line
			(start -0.12065 0.2794)
			(end -0.12065 0.3048)
			(stroke
				(width 0.1)
				(type default)
			)
			(layer "F.Fab")
		)
		(fp_line
			(start 0.67945 0.3048)
			(end 0.120396 0.3048)
			(stroke
				(width 0.1)
				(type default)
			)
			(layer "F.Fab")
		)
		(fp_line
			(start 0.120396 0.3048)
			(end 0.120396 0.2794)
			(stroke
				(width 0.1)
				(type default)
			)
			(layer "F.Fab")
		)
		(fp_line
			(start -0.12065 0.3048)
			(end -0.67945 0.3048)
			(stroke
				(width 0.1)
				(type default)
			)
			(layer "F.Fab")
		)
		(fp_line
			(start -0.67945 0.3048)
			(end -0.67945 -0.305054)
			(stroke
				(width 0.1)
				(type default)
			)
			(layer "F.Fab")
		)
		(pad "1" smd circle
			(at -0.40005 0 90)
			(size 0 0)
			(layers "F.Cu" "F.Mask" "F.Paste")
			(net "HP_LVC3_OCP_V3_2_PWRGD_R")
		)
		(pad "2" smd circle
			(at 0.40005 0 90)
			(size 0 0)
			(layers "F.Cu" "F.Mask" "F.Paste")
			(net "HP_LVC3_OCP_V3_2_FUSE_PWRGD")
		)
	)
)
